#ISCELL
  mstr_symbols cad_note *
  *
#ISCELL
  mstr_symbols design_note *
  *
#ISCELL
  mstr_symbols intel_corp_bpage *
  *
#CELL
  dev_discrete cap_a *
  page186_i10
#ISCELL
  mstr_symbols gnd *
  page186_i14
#ISCELL
  mstr_symbols gnd *
  page186_i192
#ISCELL
  mstr_symbols gnd *
  page186_i193
#ISCELL
  mstr_symbols p3v3 *
  page186_i195
#ISCELL
  mstr_standard offpage *
  page186_i217
#CELL
  mstr_discrete res *
  page186_i220
#ISCELL
  mstr_standard offpage *
  page186_i221
#CELL
  mstr_discrete res *
  page186_i222
#ISCELL
  mstr_symbols gnd *
  page186_i223
#ISCELL
  mstr_standard offpage *
  page186_i227
#ISCELL
  mstr_standard offpage *
  page186_i228
#ISCELL
  mstr_standard offpage *
  page186_i229
#ISCELL
  mstr_standard offpage *
  page186_i233
#ISCELL
  mstr_standard offpage *
  page186_i234
#ISCELL
  mstr_symbols p3v3 *
  page186_i247
#ISCELL
  mstr_standard offpage *
  page186_i249
#ISCELL
  mstr_standard offpage *
  page186_i250
#ISCELL
  mstr_standard offpage *
  page186_i251
#ISCELL
  mstr_standard offpage *
  page186_i252
#ISCELL
  mstr_standard offpage *
  page186_i254
#ISCELL
  mstr_standard offpage *
  page186_i255
#ISCELL
  mstr_standard offpage *
  page186_i256
#ISCELL
  mstr_standard offpage *
  page186_i257
#ISCELL
  mstr_standard offpage *
  page186_i267
#ISCELL
  mstr_symbols p3v3 *
  page186_i268
#ISCELL
  mstr_symbols gnd *
  page186_i269
#CELL
  dev_discrete cap_a *
  page186_i270
#ISCELL
  mstr_symbols p3v3_stby *
  page186_i274
#ISCELL
  mstr_symbols p3v3_stby *
  page186_i275
#ISCELL
  mstr_symbols p5v_stby *
  page186_i276
#ISCELL
  mstr_symbols p12v_stby *
  page186_i278
#ISCELL
  mstr_symbols p12v_stby *
  page186_i279
#ISCELL
  mstr_symbols p3v3_stby *
  page186_i296
#ISCELL
  mstr_standard tap *
  page186_i297
#ISCELL
  mstr_standard tap *
  page186_i298
#ISCELL
  mstr_standard tap *
  page186_i299
#CELL
  mstr_discrete cap *
  page186_i3
#ISCELL
  mstr_standard tap *
  page186_i300
#ISCELL
  mstr_standard tap *
  page186_i301
#ISCELL
  mstr_standard tap *
  page186_i302
#ISCELL
  mstr_standard tap *
  page186_i303
#ISCELL
  mstr_standard tap *
  page186_i304
#ISCELL
  mstr_standard tap *
  page186_i305
#ISCELL
  mstr_standard tap *
  page186_i306
#ISCELL
  mstr_standard tap *
  page186_i307
#ISCELL
  mstr_standard tap *
  page186_i308
#ISCELL
  mstr_standard tap *
  page186_i309
#ISCELL
  mstr_standard tap *
  page186_i310
#ISCELL
  mstr_standard tap *
  page186_i311
#ISCELL
  mstr_standard tap *
  page186_i312
#ISCELL
  mstr_standard offpage *
  page186_i313
#ISCELL
  mstr_standard offpage *
  page186_i314
#ISCELL
  mstr_standard tap *
  page186_i315
#ISCELL
  mstr_standard tap *
  page186_i316
#ISCELL
  mstr_standard tap *
  page186_i317
#ISCELL
  mstr_standard tap *
  page186_i318
#ISCELL
  mstr_standard offpage *
  page186_i320
#ISCELL
  mstr_standard tap *
  page186_i321
#ISCELL
  mstr_standard tap *
  page186_i322
#ISCELL
  mstr_standard tap *
  page186_i323
#ISCELL
  mstr_standard tap *
  page186_i324
#ISCELL
  mstr_standard tap *
  page186_i325
#ISCELL
  mstr_standard tap *
  page186_i326
#ISCELL
  mstr_standard tap *
  page186_i327
#ISCELL
  mstr_standard tap *
  page186_i328
#ISCELL
  mstr_standard tap *
  page186_i329
#ISCELL
  mstr_standard tap *
  page186_i330
#ISCELL
  mstr_standard tap *
  page186_i331
#ISCELL
  mstr_standard tap *
  page186_i332
#ISCELL
  mstr_standard offpage *
  page186_i333
#CELL
  dev_discrete cap_a *
  page186_i334
#CELL
  dev_discrete cap_a *
  page186_i335
#CELL
  mstr_sconn sconn120_a28699018 *
  page186_i336
#CELL
  mstr_discrete res *
  page186_i337
#CELL
  mstr_discrete res *
  page186_i338
#CELL
  mstr_discrete res *
  page186_i339
#CELL
  mstr_discrete res *
  page186_i340
#ISCELL
  mstr_standard offpage *
  page186_i341
#ISCELL
  mstr_standard offpage *
  page186_i342
#ISCELL
  mstr_standard offpage *
  page186_i343
#ISCELL
  mstr_standard offpage *
  page186_i344
#CELL
  dev_discrete cap_a *
  page186_i345
#ISCELL
  mstr_symbols gnd *
  page186_i346
#CELL
  dev_discrete cap_a *
  page186_i347
#ISCELL
  mstr_symbols p5v_stby *
  page186_i348
#CELL
  mstr_discrete cap *
  page186_i6
#CELL
  dev_discrete cap_a *
  page186_i7
#CELL
  dev_discrete cap_a *
  page186_i8
#ISCELL
  mstr_symbols gnd *
  page186_i9
